(kicad_pcb
	(version 20260206)
	(generator "pcbnew")
	(generator_version "10.0")
	(general
		(thickness 1.6)
		(legacy_teardrops no)
	)
	(paper "A4")
	(title_block
		(title "03242023_DA0F0TMBIJ0_F0T_Motherboard_J_brd_V01_OCP.brd")
		(comment 1 "Grand Teton / footprint 1682 of 6105 (U1), pads 4325-4435 of 4677")
	)
	(layers
		(0 "F.Cu" signal "TOP")
		(4 "In1.Cu" signal "GND")
		(6 "In2.Cu" signal "IN1")
		(8 "In3.Cu" signal "GND1")
		(10 "In4.Cu" signal "IN2")
		(12 "In5.Cu" signal "GND2")
		(14 "In6.Cu" signal "IN3")
		(16 "In7.Cu" signal "GND3")
		(18 "In8.Cu" signal "VCC")
		(20 "In9.Cu" signal "VCC1")
		(22 "In10.Cu" signal "GND4")
		(24 "In11.Cu" signal "IN4")
		(26 "In12.Cu" signal "GND5")
		(28 "In13.Cu" signal "IN5")
		(30 "In14.Cu" signal "GND6")
		(32 "In15.Cu" signal "IN6")
		(34 "In16.Cu" signal "GND7")
		(2 "B.Cu" signal "BOTTOM")
		(9 "F.Adhes" user "F.Adhesive")
		(11 "B.Adhes" user "B.Adhesive")
		(13 "F.Paste" user "Package Geometry/Pastemask Top")
		(15 "B.Paste" user "Package Geometry/Pastemask Bottom")
		(5 "F.SilkS" user "Ref Des/Silkscreen Top")
		(7 "B.SilkS" user "Ref Des/Silkscreen Bottom")
		(1 "F.Mask" user "Board Geometry/Soldermask Top")
		(3 "B.Mask" user "Board Geometry/Soldermask Bottom")
		(17 "Dwgs.User" user "User.Drawings")
		(19 "Cmts.User" user "User.Comments")
		(21 "Eco1.User" user "User.Eco1")
		(23 "Eco2.User" user "User.Eco2")
		(25 "Edge.Cuts" user "Board Geometry/Outline")
		(27 "Margin" user)
		(31 "F.CrtYd" user "Package Geometry/Place Bound Top")
		(29 "B.CrtYd" user "Package Geometry/Place Bound Bottom")
		(35 "F.Fab" user "Ref Des/Assembly Top")
		(33 "B.Fab" user "Ref Des/Assembly Bottom")
	)
	(footprint ""
		(layer "F.Cu")
		(at 111.93018 -251.76988 90)
		(property "Reference" "U1"
			(at -74.913236 41.548812 0)
			(unlocked yes)
			(layer "F.SilkS")
			(effects
				(font
					(size 1.6002 1.1938)
					(thickness 0.1524)
				)
				(justify left)
			)
		)
		(property "Value" ""
			(at 0 0 90)
			(layer "F.Fab")
			(effects
				(font
					(size 1.27 1.27)
				)
			)
		)
		(duplicate_pad_numbers_are_jumpers no)
		(pad "N15" smd circle
			(at -26.030682 -21.435314 270)
			(size 0.4318 0.4318)
			(layers "F.Cu" "F.Mask" "F.Paste")
			(net "GND")
		)
		(pad "N17" smd circle
			(at -24.402796 -21.435314 270)
			(size 0.4318 0.4318)
			(layers "F.Cu" "F.Mask" "F.Paste")
			(net "M_B_CPU1_SB_DQ<22>")
		)
		(pad "N19" smd circle
			(at -22.77491 -21.435314 270)
			(size 0.4318 0.4318)
			(layers "F.Cu" "F.Mask" "F.Paste")
			(net "M_B_CPU1_SB_DQ<19>")
		)
		(pad "N21" smd circle
			(at -21.147278 -21.435314 270)
			(size 0.4318 0.4318)
			(layers "F.Cu" "F.Mask" "F.Paste")
			(net "GND")
		)
		(pad "N23" smd circle
			(at -19.519392 -21.435314 270)
			(size 0.4318 0.4318)
			(layers "F.Cu" "F.Mask" "F.Paste")
			(net "M_B_CPU1_SB_DQ<14>")
		)
		(pad "N25" smd circle
			(at -17.89176 -21.435314 270)
			(size 0.4318 0.4318)
			(layers "F.Cu" "F.Mask" "F.Paste")
			(net "M_B_CPU1_SB_DQ<11>")
		)
		(pad "N27" smd circle
			(at -16.263874 -21.435314 270)
			(size 0.4318 0.4318)
			(layers "F.Cu" "F.Mask" "F.Paste")
			(net "GND")
		)
		(pad "N29" smd circle
			(at -14.635988 -21.435314 270)
			(size 0.4318 0.4318)
			(layers "F.Cu" "F.Mask" "F.Paste")
			(net "M_A_CPU1_SB_DQ<6>")
		)
		(pad "N31" smd circle
			(at -13.008356 -21.435314 270)
			(size 0.4318 0.4318)
			(layers "F.Cu" "F.Mask" "F.Paste")
			(net "M_A_CPU1_SB_DQ<3>")
		)
		(pad "N33" smd circle
			(at -11.380724 -21.435314 270)
			(size 0.4318 0.4318)
			(layers "F.Cu" "F.Mask" "F.Paste")
			(net "GND")
		)
		(pad "N35" smd circle
			(at -9.752838 -21.435314 270)
			(size 0.4318 0.4318)
			(layers "F.Cu" "F.Mask" "F.Paste")
			(net "M_B_CPU1_SB_CB<2>")
		)
		(pad "N37" smd circle
			(at -8.124952 -21.435314 270)
			(size 0.4318 0.4318)
			(layers "F.Cu" "F.Mask" "F.Paste")
			(net "M_B_CPU1_SB_CB<7>")
		)
		(pad "N39" smd circle
			(at -6.49732 -21.435314 270)
			(size 0.4318 0.4318)
			(layers "F.Cu" "F.Mask" "F.Paste")
			(net "GND")
		)
		(pad "N41" smd circle
			(at -4.869434 -21.435314 270)
			(size 0.4318 0.4318)
			(layers "F.Cu" "F.Mask" "F.Paste")
			(net "M_B_CPU1_SB_CS_N<2>")
		)
		(pad "N43" smd circle
			(at -3.241802 -21.435314 270)
			(size 0.4318 0.4318)
			(layers "F.Cu" "F.Mask" "F.Paste")
			(net "M_B_CPU1_SB_CA<5>")
		)
		(pad "N45" smd circle
			(at -1.613916 -21.435314 270)
			(size 0.4318 0.4318)
			(layers "F.Cu" "F.Mask" "F.Paste")
			(net "GND")
		)
		(pad "N48" smd circle
			(at 2.427732 -21.325332 270)
			(size 0.4318 0.4318)
			(layers "F.Cu" "F.Mask" "F.Paste")
			(net "M_B_CPU1_SA_CA<3>")
		)
		(pad "N50" smd circle
			(at 4.055618 -21.325332 270)
			(size 0.4318 0.4318)
			(layers "F.Cu" "F.Mask" "F.Paste")
			(net "M_B_CPU1_SA_CS_N<3>")
		)
		(pad "N52" smd circle
			(at 5.68325 -21.325332 270)
			(size 0.4318 0.4318)
			(layers "F.Cu" "F.Mask" "F.Paste")
			(net "GND")
		)
		(pad "N54" smd circle
			(at 7.311136 -21.325332 270)
			(size 0.4318 0.4318)
			(layers "F.Cu" "F.Mask" "F.Paste")
			(net "M_B_CPU1_SA_CB<6>")
		)
		(pad "N56" smd circle
			(at 8.939022 -21.325332 270)
			(size 0.4318 0.4318)
			(layers "F.Cu" "F.Mask" "F.Paste")
			(net "M_B_CPU1_SA_CB<3>")
		)
		(pad "N58" smd circle
			(at 10.566654 -21.325332 270)
			(size 0.4318 0.4318)
			(layers "F.Cu" "F.Mask" "F.Paste")
			(net "GND")
		)
		(pad "N60" smd circle
			(at 12.19454 -21.325332 270)
			(size 0.4318 0.4318)
			(layers "F.Cu" "F.Mask" "F.Paste")
			(net "M_B_CPU1_SA_DQ<22>")
		)
		(pad "N62" smd circle
			(at 13.822426 -21.325332 270)
			(size 0.4318 0.4318)
			(layers "F.Cu" "F.Mask" "F.Paste")
			(net "M_B_CPU1_SA_DQ<19>")
		)
		(pad "N64" smd circle
			(at 15.450058 -21.325332 270)
			(size 0.4318 0.4318)
			(layers "F.Cu" "F.Mask" "F.Paste")
			(net "GND")
		)
		(pad "N66" smd circle
			(at 17.07769 -21.325332 270)
			(size 0.4318 0.4318)
			(layers "F.Cu" "F.Mask" "F.Paste")
			(net "M_A_CPU1_SA_DQ<14>")
		)
		(pad "N68" smd circle
			(at 18.705576 -21.325332 270)
			(size 0.4318 0.4318)
			(layers "F.Cu" "F.Mask" "F.Paste")
			(net "M_A_CPU1_SA_DQ<11>")
		)
		(pad "N70" smd circle
			(at 20.333462 -21.325332 270)
			(size 0.4318 0.4318)
			(layers "F.Cu" "F.Mask" "F.Paste")
			(net "GND")
		)
		(pad "N72" smd circle
			(at 21.961094 -21.325332 270)
			(size 0.4318 0.4318)
			(layers "F.Cu" "F.Mask" "F.Paste")
			(net "M_B_CPU1_SA_DQ<6>")
		)
		(pad "N74" smd circle
			(at 23.58898 -21.325332 270)
			(size 0.4318 0.4318)
			(layers "F.Cu" "F.Mask" "F.Paste")
			(net "M_B_CPU1_SA_DQ<3>")
		)
		(pad "N76" smd circle
			(at 25.216612 -21.325332 270)
			(size 0.4318 0.4318)
			(layers "F.Cu" "F.Mask" "F.Paste")
			(net "GND")
		)
		(pad "N78" smd circle
			(at 26.844498 -21.325332 270)
			(size 0.4318 0.4318)
			(layers "F.Cu" "F.Mask" "F.Paste")
			(net "GND")
		)
		(pad "N80" smd circle
			(at 28.472384 -21.325332 270)
			(size 0.4318 0.4318)
			(layers "F.Cu" "F.Mask" "F.Paste")
			(net "GND")
		)
		(pad "N82" smd circle
			(at 30.100016 -21.325332 270)
			(size 0.4318 0.4318)
			(layers "F.Cu" "F.Mask" "F.Paste")
			(net "GND")
		)
		(pad "N84" smd circle
			(at 31.727902 -21.325332 270)
			(size 0.4318 0.4318)
			(layers "F.Cu" "F.Mask" "F.Paste")
			(net "GND")
		)
		(pad "N86" smd circle
			(at 33.355534 -21.325332 270)
			(size 0.4318 0.4318)
			(layers "F.Cu" "F.Mask" "F.Paste")
			(net "P5E_CPU1_PE4_TX_DP<1>")
		)
		(pad "N88" smd circle
			(at 34.98342 -21.325332 270)
			(size 0.4318 0.4318)
			(layers "F.Cu" "F.Mask" "F.Paste")
			(net "GND")
		)
		(pad "N90" smd oval
			(at 36.611306 -21.325332)
			(size 0.381 0.4826)
			(drill
				(offset 0 -0.0508)
			)
			(layers "F.Cu" "F.Mask" "F.Paste")
			(net "P5E_CPU1_PE4_RX_DP<1>")
		)
		(pad "P2" smd circle
			(at -36.611306 -20.965668 270)
			(size 0.4318 0.4318)
			(layers "F.Cu" "F.Mask" "F.Paste")
			(net "UPI_CPU1_CPU0_P0P1_DP<2>")
		)
		(pad "P4" smd circle
			(at -34.98342 -20.965668 270)
			(size 0.4318 0.4318)
			(layers "F.Cu" "F.Mask" "F.Paste")
			(net "GND")
		)
		(pad "P6" smd circle
			(at -33.355534 -20.965668 270)
			(size 0.4318 0.4318)
			(layers "F.Cu" "F.Mask" "F.Paste")
			(net "UPI_CPU0_CPU1_P1P0_DN<2>")
		)
		(pad "P8" smd circle
			(at -31.727902 -20.965668 270)
			(size 0.4318 0.4318)
			(layers "F.Cu" "F.Mask" "F.Paste")
			(net "GND")
		)
		(pad "P10" smd circle
			(at -30.100016 -20.965668 270)
			(size 0.4318 0.4318)
			(layers "F.Cu" "F.Mask" "F.Paste")
			(net "P5E_CPU1_PE0_RX_DN<2>")
		)
		(pad "P12" smd circle
			(at -28.472384 -20.965668 270)
			(size 0.4318 0.4318)
			(layers "F.Cu" "F.Mask" "F.Paste")
			(net "GND")
		)
		(pad "P14" smd circle
			(at -26.844498 -20.965668 270)
			(size 0.4318 0.4318)
			(layers "F.Cu" "F.Mask" "F.Paste")
			(net "P5E_CPU1_PE0_TX_DN<1>")
		)
		(pad "P16" smd circle
			(at -25.216612 -20.965668 270)
			(size 0.4318 0.4318)
			(layers "F.Cu" "F.Mask" "F.Paste")
			(net "GND")
		)
		(pad "P18" smd circle
			(at -23.58898 -20.965668 270)
			(size 0.4318 0.4318)
			(layers "F.Cu" "F.Mask" "F.Paste")
			(net "M_B_CPU1_SB_DQS_DP<7>")
		)
		(pad "P20" smd circle
			(at -21.961094 -20.965668 270)
			(size 0.4318 0.4318)
			(layers "F.Cu" "F.Mask" "F.Paste")
			(net "GND")
		)
		(pad "P22" smd circle
			(at -20.333462 -20.965668 270)
			(size 0.4318 0.4318)
			(layers "F.Cu" "F.Mask" "F.Paste")
			(net "GND")
		)
		(pad "P24" smd circle
			(at -18.705576 -20.965668 270)
			(size 0.4318 0.4318)
			(layers "F.Cu" "F.Mask" "F.Paste")
			(net "M_B_CPU1_SB_DQS_DP<6>")
		)
		(pad "P26" smd circle
			(at -17.07769 -20.965668 270)
			(size 0.4318 0.4318)
			(layers "F.Cu" "F.Mask" "F.Paste")
			(net "GND")
		)
		(pad "P28" smd circle
			(at -15.450058 -20.965668 270)
			(size 0.4318 0.4318)
			(layers "F.Cu" "F.Mask" "F.Paste")
			(net "GND")
		)
		(pad "P30" smd circle
			(at -13.822426 -20.965668 270)
			(size 0.4318 0.4318)
			(layers "F.Cu" "F.Mask" "F.Paste")
			(net "M_A_CPU1_SB_DQS_DP<5>")
		)
		(pad "P32" smd circle
			(at -12.19454 -20.965668 270)
			(size 0.4318 0.4318)
			(layers "F.Cu" "F.Mask" "F.Paste")
			(net "GND")
		)
		(pad "P34" smd circle
			(at -10.566654 -20.965668 270)
			(size 0.4318 0.4318)
			(layers "F.Cu" "F.Mask" "F.Paste")
			(net "GND")
		)
		(pad "P36" smd circle
			(at -8.939022 -20.965668 270)
			(size 0.4318 0.4318)
			(layers "F.Cu" "F.Mask" "F.Paste")
			(net "M_B_CPU1_SB_DQS_DN<4>")
		)
		(pad "P38" smd circle
			(at -7.311136 -20.965668 270)
			(size 0.4318 0.4318)
			(layers "F.Cu" "F.Mask" "F.Paste")
			(net "GND")
		)
		(pad "P40" smd circle
			(at -5.68325 -20.965668 270)
			(size 0.4318 0.4318)
			(layers "F.Cu" "F.Mask" "F.Paste")
			(net "GND")
		)
		(pad "P42" smd circle
			(at -4.055618 -20.965668 270)
			(size 0.4318 0.4318)
			(layers "F.Cu" "F.Mask" "F.Paste")
			(net "M_B_CPU1_SB_PAR")
		)
		(pad "P44" smd circle
			(at -2.427732 -20.965668 270)
			(size 0.4318 0.4318)
			(layers "F.Cu" "F.Mask" "F.Paste")
			(net "GND")
		)
		(pad "P47" smd circle
			(at 1.613916 -20.855686 270)
			(size 0.4318 0.4318)
			(layers "F.Cu" "F.Mask" "F.Paste")
			(net "GND")
		)
		(pad "P49" smd circle
			(at 3.241802 -20.855686 270)
			(size 0.4318 0.4318)
			(layers "F.Cu" "F.Mask" "F.Paste")
			(net "M_B_CPU1_SA_CA<1>")
		)
		(pad "P51" smd circle
			(at 4.869434 -20.855686 270)
			(size 0.4318 0.4318)
			(layers "F.Cu" "F.Mask" "F.Paste")
			(net "GND")
		)
		(pad "P53" smd circle
			(at 6.49732 -20.855686 270)
			(size 0.4318 0.4318)
			(layers "F.Cu" "F.Mask" "F.Paste")
			(net "GND")
		)
		(pad "P55" smd circle
			(at 8.124952 -20.855686 270)
			(size 0.4318 0.4318)
			(layers "F.Cu" "F.Mask" "F.Paste")
			(net "M_B_CPU1_SA_DQS_DP<9>")
		)
		(pad "P57" smd circle
			(at 9.752838 -20.855686 270)
			(size 0.4318 0.4318)
			(layers "F.Cu" "F.Mask" "F.Paste")
			(net "GND")
		)
		(pad "P59" smd circle
			(at 11.380724 -20.855686 270)
			(size 0.4318 0.4318)
			(layers "F.Cu" "F.Mask" "F.Paste")
			(net "GND")
		)
		(pad "P61" smd circle
			(at 13.008356 -20.855686 270)
			(size 0.4318 0.4318)
			(layers "F.Cu" "F.Mask" "F.Paste")
			(net "M_B_CPU1_SA_DQS_DP<7>")
		)
		(pad "P63" smd circle
			(at 14.635988 -20.855686 270)
			(size 0.4318 0.4318)
			(layers "F.Cu" "F.Mask" "F.Paste")
			(net "GND")
		)
		(pad "P65" smd circle
			(at 16.263874 -20.855686 270)
			(size 0.4318 0.4318)
			(layers "F.Cu" "F.Mask" "F.Paste")
			(net "GND")
		)
		(pad "P67" smd circle
			(at 17.89176 -20.855686 270)
			(size 0.4318 0.4318)
			(layers "F.Cu" "F.Mask" "F.Paste")
			(net "M_A_CPU1_SA_DQS_DN<6>")
		)
		(pad "P69" smd circle
			(at 19.519392 -20.855686 270)
			(size 0.4318 0.4318)
			(layers "F.Cu" "F.Mask" "F.Paste")
			(net "GND")
		)
		(pad "P71" smd circle
			(at 21.147278 -20.855686 270)
			(size 0.4318 0.4318)
			(layers "F.Cu" "F.Mask" "F.Paste")
			(net "GND")
		)
		(pad "P73" smd circle
			(at 22.77491 -20.855686 270)
			(size 0.4318 0.4318)
			(layers "F.Cu" "F.Mask" "F.Paste")
			(net "M_B_CPU1_SA_DQS_DP<5>")
		)
		(pad "P75" smd circle
			(at 24.402796 -20.855686 270)
			(size 0.4318 0.4318)
			(layers "F.Cu" "F.Mask" "F.Paste")
			(net "GND")
		)
		(pad "P77" smd circle
			(at 26.030682 -20.855686 270)
			(size 0.4318 0.4318)
			(layers "F.Cu" "F.Mask" "F.Paste")
			(net "GND")
		)
		(pad "P79" smd circle
			(at 27.658314 -20.855686 270)
			(size 0.4318 0.4318)
			(layers "F.Cu" "F.Mask" "F.Paste")
			(net "PVCCFA_EHV_FIVRA_CPU1")
		)
		(pad "P81" smd circle
			(at 29.2862 -20.855686 270)
			(size 0.4318 0.4318)
			(layers "F.Cu" "F.Mask" "F.Paste")
			(net "UPI_CPU1_CPU0_P2P2_DN<5>")
		)
		(pad "P83" smd circle
			(at 30.914086 -20.855686 270)
			(size 0.4318 0.4318)
			(layers "F.Cu" "F.Mask" "F.Paste")
			(net "UPI_CPU1_CPU0_P2P2_DP<6>")
		)
		(pad "P85" smd circle
			(at 32.541718 -20.855686 270)
			(size 0.4318 0.4318)
			(layers "F.Cu" "F.Mask" "F.Paste")
			(net "P5E_CPU1_PE4_TX_DN<1>")
		)
		(pad "P87" smd circle
			(at 34.169604 -20.855686 270)
			(size 0.4318 0.4318)
			(layers "F.Cu" "F.Mask" "F.Paste")
			(net "GND")
		)
		(pad "P89" smd circle
			(at 35.797236 -20.855686 270)
			(size 0.4318 0.4318)
			(layers "F.Cu" "F.Mask" "F.Paste")
			(net "P5E_CPU1_PE4_RX_DN<1>")
		)
		(pad "P91" smd oval
			(at 37.425122 -20.855686)
			(size 0.381 0.4826)
			(drill
				(offset 0 -0.0508)
			)
			(layers "F.Cu" "F.Mask" "F.Paste")
			(net "GND")
		)
		(pad "R1" smd oval
			(at -37.425122 -20.495514 180)
			(size 0.381 0.4826)
			(drill
				(offset 0 -0.0508)
			)
			(layers "F.Cu" "F.Mask" "F.Paste")
			(net "GND")
		)
		(pad "R3" smd circle
			(at -35.797236 -20.495514 270)
			(size 0.4318 0.4318)
			(layers "F.Cu" "F.Mask" "F.Paste")
			(net "UPI_CPU1_CPU0_P0P1_DP<3>")
		)
		(pad "R5" smd circle
			(at -34.169604 -20.495514 270)
			(size 0.4318 0.4318)
			(layers "F.Cu" "F.Mask" "F.Paste")
			(net "GND")
		)
		(pad "R7" smd circle
			(at -32.541718 -20.495514 270)
			(size 0.4318 0.4318)
			(layers "F.Cu" "F.Mask" "F.Paste")
			(net "UPI_CPU0_CPU1_P1P0_DP<2>")
		)
		(pad "R9" smd circle
			(at -30.914086 -20.495514 270)
			(size 0.4318 0.4318)
			(layers "F.Cu" "F.Mask" "F.Paste")
			(net "GND")
		)
		(pad "R11" smd circle
			(at -29.2862 -20.495514 270)
			(size 0.4318 0.4318)
			(layers "F.Cu" "F.Mask" "F.Paste")
			(net "P5E_CPU1_PE0_RX_DP<2>")
		)
		(pad "R13" smd circle
			(at -27.658314 -20.495514 270)
			(size 0.4318 0.4318)
			(layers "F.Cu" "F.Mask" "F.Paste")
			(net "GND")
		)
		(pad "R15" smd circle
			(at -26.030682 -20.495514 270)
			(size 0.4318 0.4318)
			(layers "F.Cu" "F.Mask" "F.Paste")
			(net "P5E_CPU1_PE0_TX_DP<1>")
		)
		(pad "R17" smd circle
			(at -24.402796 -20.495514 270)
			(size 0.4318 0.4318)
			(layers "F.Cu" "F.Mask" "F.Paste")
			(net "GND")
		)
		(pad "R19" smd circle
			(at -22.77491 -20.495514 270)
			(size 0.4318 0.4318)
			(layers "F.Cu" "F.Mask" "F.Paste")
			(net "GND")
		)
		(pad "R21" smd circle
			(at -21.147278 -20.495514 270)
			(size 0.4318 0.4318)
			(layers "F.Cu" "F.Mask" "F.Paste")
			(net "M_C_CPU1_SB_DQS_DN<2>")
		)
		(pad "R23" smd circle
			(at -19.519392 -20.495514 270)
			(size 0.4318 0.4318)
			(layers "F.Cu" "F.Mask" "F.Paste")
			(net "GND")
		)
		(pad "R25" smd circle
			(at -17.89176 -20.495514 270)
			(size 0.4318 0.4318)
			(layers "F.Cu" "F.Mask" "F.Paste")
			(net "GND")
		)
		(pad "R27" smd circle
			(at -16.263874 -20.495514 270)
			(size 0.4318 0.4318)
			(layers "F.Cu" "F.Mask" "F.Paste")
			(net "M_B_CPU1_SB_DQS_DN<0>")
		)
		(pad "R29" smd circle
			(at -14.635988 -20.495514 270)
			(size 0.4318 0.4318)
			(layers "F.Cu" "F.Mask" "F.Paste")
			(net "GND")
		)
		(pad "R31" smd circle
			(at -13.008356 -20.495514 270)
			(size 0.4318 0.4318)
			(layers "F.Cu" "F.Mask" "F.Paste")
			(net "GND")
		)
		(pad "R33" smd circle
			(at -11.380724 -20.495514 270)
			(size 0.4318 0.4318)
			(layers "F.Cu" "F.Mask" "F.Paste")
			(net "M_C_CPU1_SB_DQS_DN<9>")
		)
		(pad "R35" smd circle
			(at -9.752838 -20.495514 270)
			(size 0.4318 0.4318)
			(layers "F.Cu" "F.Mask" "F.Paste")
			(net "GND")
		)
		(pad "R37" smd circle
			(at -8.124952 -20.495514 270)
			(size 0.4318 0.4318)
			(layers "F.Cu" "F.Mask" "F.Paste")
			(net "GND")
		)
		(pad "R39" smd circle
			(at -6.49732 -20.495514 270)
			(size 0.4318 0.4318)
			(layers "F.Cu" "F.Mask" "F.Paste")
			(net "M_C_CPU1_SB_CA<6>")
		)
		(pad "R41" smd circle
			(at -4.869434 -20.495514 270)
			(size 0.4318 0.4318)
			(layers "F.Cu" "F.Mask" "F.Paste")
			(net "GND")
		)
		(pad "R43" smd circle
			(at -3.241802 -20.495514 270)
			(size 0.4318 0.4318)
			(layers "F.Cu" "F.Mask" "F.Paste")
			(net "GND")
		)
		(pad "R45" smd circle
			(at -1.613916 -20.495514 270)
			(size 0.4318 0.4318)
			(layers "F.Cu" "F.Mask" "F.Paste")
			(net "M_B_CPU1_CLK_DN<0>")
		)
		(pad "R48" smd circle
			(at 2.427732 -20.385532 270)
			(size 0.4318 0.4318)
			(layers "F.Cu" "F.Mask" "F.Paste")
			(net "GND")
		)
		(pad "R50" smd circle
			(at 4.055618 -20.385532 270)
			(size 0.4318 0.4318)
			(layers "F.Cu" "F.Mask" "F.Paste")
			(net "GND")
		)
		(pad "R52" smd circle
			(at 5.68325 -20.385532 270)
			(size 0.4318 0.4318)
			(layers "F.Cu" "F.Mask" "F.Paste")
			(net "M_C_CPU1_SA_CA<0>")
		)
		(pad "R54" smd circle
			(at 7.311136 -20.385532 270)
			(size 0.4318 0.4318)
			(layers "F.Cu" "F.Mask" "F.Paste")
			(net "GND")
		)
		(pad "R56" smd circle
			(at 8.939022 -20.385532 270)
			(size 0.4318 0.4318)
			(layers "F.Cu" "F.Mask" "F.Paste")
			(net "GND")
		)
	)
)
